# BASEBOARD_FAB2 (Tioga Pass) — schematic parts with pin connectivity, parts 4665–4665 of 4751; source: Cadence DE-HDL packaged netlist (pstxprt.dat, pstxnet.dat, pstchip.dat)

U5D1  SKX_EXT_B  IC  pkg BGA1  page 21  (pins 340-678 of 3647)
  AH55  RSVD(231)  BI  = TP_CPU0_RSVD_231
  AH57  RSVD(230)  BI  = TP_CPU0_RSVD_230
  AH59  VSS(821)  GROUND  = GND
  AH61  VSS(820)  GROUND  = GND
  AH63  DDR2_CAVREF  OUT  = M_C_CPU_VREF
  AH65  VSS(819)  GROUND  = GND
  AH67  DDR0_DQS_DN(8)  BI  = M_A_DQS_DN<8>
  AH69  VSS(818)  GROUND  = GND
  AH71  RSVD(229)  BI  = TP_CPU0_RSVD_229
  AH73  RSVD(228)  BI  = TP_CPU0_RSVD_228
  AH75  VSS(817)  GROUND  = GND
  AH77  VSS(816)  GROUND  = GND
  AH79  DDR1_DQ(13)  BI  = M_B_DQ<13>
  AH81  DDR1_DQ(8)  BI  = M_B_DQ<8>
  AH83  VSS(815)  GROUND  = GND
  AH85  DDR0_DQS_DP(0)  BI  = M_A_DQS_DP<0>
  AJ2  UPI0_TX_DP(8)  OUT  = UPI_CPU0_CPU1_P0P0_DP<11>
  AJ4  VSS(1189)  GROUND  = GND
  AJ6  UPI0_RX_DN(6)  IN  = UPI_CPU1_CPU0_P0P0_DN<13>
  AJ8  VSS(814)  GROUND  = GND
  AJ10  BPM_N(0)  BI  = XDP_CPU_MBP0_N
  AJ12  ERROR_N(0)  OUT  = H_CPU0_ERR0_G_N
  AJ14  EAR_N  IN  = PD_CPU0_EAR_N
  AJ18  DDR012_SPDSCL  BI  = SMB_DDR_ABC_SCL_G_R
  AJ20  RSVD(227)  BI  = TP_CPU0_RSVD_227
  AJ22  VSS(813)  GROUND  = GND
  AJ24  DDR2_DQS_DN(7)  BI  = M_C_DQS_DN<7>
  AJ26  VSS(812)  GROUND  = GND
  AJ28  VSS(811)  GROUND  = GND
  AJ30  DDR2_DQS_DN(6)  BI  = M_C_DQS_DN<6>
  AJ32  VSS(810)  GROUND  = GND
  AJ34  VSS(809)  GROUND  = GND
  AJ36  VCCIN(260)  POWER  = PVCCIN_CPU0
  AJ46  VSS(808)  GROUND  = GND
  AJ48  VSS(807)  GROUND  = GND
  AJ50  VSS(806)  GROUND  = GND
  AJ52  VSS(805)  GROUND  = GND
  AJ54  VSS(804)  GROUND  = GND
  AJ56  RSVD(226)  BI  = TP_CPU0_RSVD_226
  AJ58  RSVD(225)  BI  = TP_CPU0_RSVD_225
  AJ60  RSVD(224)  BI  = TP_CPU0_RSVD_224
  AJ62  RSVD(223)  BI  = TP_CPU0_RSVD_223
  AJ64  DDR0_CAVREF  OUT  = M_A_CPU_VREF
  AJ66  VSS(803)  GROUND  = GND
  AJ68  VSS(802)  GROUND  = GND
  AJ70  RSVD(222)  BI  = TP_CPU0_RSVD_222
  AJ74  VSS(801)  GROUND  = GND
  AJ76  DDR2_DQ(3)  BI  = M_C_DQ<3>
  AJ78  VSS(800)  GROUND  = GND
  AJ80  DDR1_DQ(12)  BI  = M_B_DQ<12>
  AJ82  VSS(799)  GROUND  = GND
  AJ84  DDR0_DQS_DN(0)  BI  = M_A_DQS_DN<0>
  AJ86  VSS(798)  GROUND  = GND
  AK1  UPI0_TX_DP(9)  OUT  = UPI_CPU0_CPU1_P0P0_DP<10>
  AK3  UPI0_TX_DP(10)  OUT  = UPI_CPU0_CPU1_P0P0_DP<9>
  AK5  UPI0_RX_DP(7)  IN  = UPI_CPU1_CPU0_P0P0_DP<12>
  AK7  UPI0_RX_DN(8)  IN  = UPI_CPU1_CPU0_P0P0_DN<11>
  AK9  VSS(797)  GROUND  = GND
  AK11  ERROR_N(1)  OUT  = H_CPU0_ERR1_G_N
  AK13  VSS(796)  GROUND  = GND
  AK19  VSS(795)  GROUND  = GND
  AK21  RSVD(221)  BI  = VSENSE_P1V8MCP_CPU0_SKT_VSEN
  AK23  VSS(794)  GROUND  = GND
  AK25  VSS(793)  GROUND  = GND
  AK27  RSVD(220)  BI  = CLK_322M_OSC_CPU0_RC_DP
  AK29  VSS(792)  GROUND  = GND
  AK31  VSS(791)  GROUND  = GND
  AK33  VSS(790)  GROUND  = GND
  AK35  VCCIN(259)  POWER  = PVCCIN_CPU0
  AK45  VCCIN(258)  POWER  = PVCCIN_CPU0
  AK47  VCCIN(257)  POWER  = PVCCIN_CPU0
  AK49  VCCIN(256)  POWER  = PVCCIN_CPU0
  AK51  VCCIN(255)  POWER  = PVCCIN_CPU0
  AK53  VCCIN(254)  POWER  = PVCCIN_CPU0
  AK55  VSS(789)  GROUND  = GND
  AK57  RSVD(219)  BI  = TP_CPU0_RSVD_219
  AK59  RSVD(218)  BI  = TP_CPU0_RSVD_218
  AK61  RSVD(217)  BI  = TP_CPU0_RSVD_217
  AK63  DDR1_CAVREF  OUT  = M_B_CPU_VREF
  AK65  VSS(788)  GROUND  = GND
  AK67  VSS(787)  GROUND  = GND
  AK69  RSVD(216)  BI  = TP_CPU0_RSVD_216
  AK73  VSS(786)  GROUND  = GND
  AK75  DDR2_DQ(7)  BI  = M_C_DQ<7>
  AK77  DDR2_DQ(2)  BI  = M_C_DQ<2>
  AK79  VSS(785)  GROUND  = GND
  AK81  VSS(784)  GROUND  = GND
  AK83  VSS(783)  GROUND  = GND
  AK85  VSS(782)  GROUND  = GND
  AL2  UPI0_TX_DN(9)  OUT  = UPI_CPU0_CPU1_P0P0_DN<10>
  AL4  VSS(781)  GROUND  = GND
  AL6  UPI0_RX_DN(7)  IN  = UPI_CPU1_CPU0_P0P0_DN<12>
  AL8  UPI0_RX_DP(9)  IN  = UPI_CPU1_CPU0_P0P0_DP<10>
  AL10  VSS(780)  GROUND  = GND
  AL12  ERROR_N(2)  OUT  = H_CPU0_ERR2_G_N
  AL14  CATERR_N  BI  = H_CPU0_CATERR_G_N
  AL18  PE_HP_SDA  BI  = SMB_CPU0_PE_HP_GTL_SDA
  AL20  RSVD(215)  BI  = VSENSE_P1V8MCP_CPU0_SKT_VRTN
  AL22  RSVD(214)  BI  = TP_CPU0_RSVD_214
  AL24  VSS(779)  GROUND  = GND
  AL26  RSVD(213)  BI  = CLK_322M_OSC_CPU0_RC_DN
  AL28  VCCIO(103)  POWER  = PVCCIO_CPU0
  AL30  VSS(778)  GROUND  = GND
  AL32  VSS(777)  GROUND  = GND
  AL34  VCCIN(253)  POWER  = PVCCIN_CPU0
  AL46  VCCIN(252)  POWER  = PVCCIN_CPU0
  AL48  VCCIN(251)  POWER  = PVCCIN_CPU0
  AL50  VCCIN(250)  POWER  = PVCCIN_CPU0
  AL52  VCCIN(249)  POWER  = PVCCIN_CPU0
  AL54  VCCIN(248)  POWER  = PVCCIN_CPU0
  AL56  VSS(776)  GROUND  = GND
  AL58  RSVD(212)  BI  = TP_CPU0_RSVD_212
  AL60  RSVD(211)  BI  = TP_CPU0_RSVD_211
  AL62  RSVD(210)  BI  = TP_CPU0_RSVD_210
  AL64  VSS(775)  GROUND  = GND
  AL66  DDR2_DQS_DN(12)  BI  = M_C_DQS_DN<12>
  AL68  VSS(774)  GROUND  = GND
  AL74  DDR2_DQS_DN(0)  BI  = M_C_DQS_DN<0>
  AL76  VSS(773)  GROUND  = GND
  AL78  VSS(772)  GROUND  = GND
  AL80  VSS(771)  GROUND  = GND
  AL82  VSS(770)  GROUND  = GND
  AL84  DDR0_DQS_DN(9)  BI  = M_A_DQS_DN<9>
  AL86  VSS(769)  GROUND  = GND
  AM1  VSS(768)  GROUND  = GND
  AM3  UPI0_TX_DN(10)  OUT  = UPI_CPU0_CPU1_P0P0_DN<9>
  AM5  VCCIO(4)  POWER  = PVCCIO_CPU0
  AM7  UPI0_RX_DP(8)  IN  = UPI_CPU1_CPU0_P0P0_DP<11>
  AM9  UPI0_RX_DN(9)  IN  = UPI_CPU1_CPU0_P0P0_DN<10>
  AM11  TSC_SYNC  BI  = PU_CPU0_TSC_SYNC
  AM13  TEST_3  BI  = TP_CPU0_RSVD_TEST_3
  AM19  PE_HP_SCL  BI  = SMB_CPU0_PE_HP_GTL_SCL
  AM21  RSVD(209)  BI  = PVCCMCP_CPU0
  AM23  RSVD(208)  BI  = TP_CPU0_RSVD_208
  AM25  RSVD(207)  BI  = PVCCMCP_CPU0
  AM27  RSVD(206)  BI  = CLK_100M_CPU0_RC_REFCLK0_DP
  AM29  VCCIO(102)  POWER  = PVCCIO_CPU0
  AM31  VSS(766)  GROUND  = GND
  AM33  VCCIN(247)  POWER  = PVCCIN_CPU0
  AM53  VCCIN(246)  POWER  = PVCCIN_CPU0
  AM55  VCCIN(245)  POWER  = PVCCIN_CPU0
  AM57  VSS(765)  GROUND  = GND
  AM59  RSVD(205)  BI  = TP_CPU0_RSVD_205
  AM61  RSVD(204)  BI  = TP_CPU0_RSVD_204
  AM63  VSS(764)  GROUND  = GND
  AM65  DDR2_DQ(30)  BI  = M_C_DQ<30>
  AM67  DDR2_DQ(24)  BI  = M_C_DQ<24>
  AM69  VSS(763)  GROUND  = GND
  AM73  VSS(762)  GROUND  = GND
  AM75  DDR2_DQS_DP(0)  BI  = M_C_DQS_DP<0>
  AM77  DDR2_DQ(6)  BI  = M_C_DQ<6>
  AM79  VSS(761)  GROUND  = GND
  AM81  DDR1_DQ(3)  BI  = M_B_DQ<3>
  AM83  VSS(760)  GROUND  = GND
  AM85  DDR0_DQS_DP(9)  BI  = M_A_DQS_DP<9>
  AN2  VSS(759)  GROUND  = GND
  AN4  UPI0_TX_DN(11)  OUT  = UPI_CPU0_CPU1_P0P0_DN<8>
  AN6  VSS(758)  GROUND  = GND
  AN8  UPI0_RX_DP(10)  IN  = UPI_CPU1_CPU0_P0P0_DP<9>
  AN10  VCCIO(40)  POWER  = PVCCIO_CPU0
  AN12  TEST_4  BI  = TP_CPU0_RSVD_TEST_4
  AN14  TEST_5  BI  = TP_CPU0_RSVD_TEST_5
  AN18  RSVD(203)  BI  = PVCCMCP_CPU0
  AN20  MSMI_N  BI  = H_CPU0_MSMI_G_N
  AN22  RSVD(202)  BI  = PVCCMCP_CPU0
  AN24  RSVD(201)  BI  = PVCCMCP_CPU0
  AN26  RSVD(200)  BI  = PVCCMCP_CPU0
  AN28  VSS(757)  GROUND  = GND
  AN30  DDR012_DRAM_PWR_OK  IN  = PWRGD_CPU0_DRAMPWROK_ABC_G
  AN32  VCCIN(244)  POWER  = PVCCIN_CPU0
  AN54  VCCIN(243)  POWER  = PVCCIN_CPU0
  AN56  VCCIN(242)  POWER  = PVCCIN_CPU0
  AN58  VSS(756)  GROUND  = GND
  AN60  RSVD(199)  BI  = TP_CPU0_RSVD_199
  AN62  RSVD(198)  BI  = TP_CPU0_RSVD_198
  AN64  DDR2_DQ(26)  BI  = M_C_DQ<26>
  AN66  DDR2_DQS_DP(12)  BI  = M_C_DQS_DP<12>
  AN68  DDR2_DQ(28)  BI  = M_C_DQ<28>
  AN74  DDR2_DQ(1)  BI  = M_C_DQ<1>
  AN76  DDR2_DQS_DP(9)  BI  = M_C_DQS_DP<9>
  AN78  VSS(755)  GROUND  = GND
  AN80  DDR1_DQ(7)  BI  = M_B_DQ<7>
  AN82  DDR1_DQ(2)  BI  = M_B_DQ<2>
  AN84  DDR0_DQ(1)  BI  = M_A_DQ<1>
  AN86  DDR0_DQ(0)  BI  = M_A_DQ<0>
  AP1  UPI0_TX_DP(12)  OUT  = UPI_CPU0_CPU1_P0P0_DP<7>
  AP3  UPI0_TX_DP(11)  OUT  = UPI_CPU0_CPU1_P0P0_DP<8>
  AP5  VSS(754)  GROUND  = GND
  AP7  UPI0_RX_DN(10)  IN  = UPI_CPU1_CPU0_P0P0_DN<9>
  AP9  VSS(753)  GROUND  = GND
  AP11  NMI  IN  = TP_NMI_CPU0
  AP13  VSS(752)  GROUND  = GND
  AP17  PWR_DEBUG_N  IN  = XDP_CPU_PWR_DEBUG_N
  AP19  VSS(751)  GROUND  = GND
  AP21  RESET_N  IN  = RST_CPU0_G_N
  AP23  RSVD(197)  BI  = PVCCMCP_CPU0
  AP25  RSVD(196)  BI  = PVCCMCP_CPU0
  AP27  RSVD(195)  BI  = CLK_100M_CPU0_RC_REFCLK0_DN
  AP29  UPI01_RBIAS(1)  IN  = A_CPU0_UPI01_RBIAS
  AP31  VSS(750)  GROUND  = GND
  AP55  VCCIN(241)  POWER  = PVCCIN_CPU0
  AP57  VCCIN(240)  POWER  = PVCCIN_CPU0
  AP59  VSS(749)  GROUND  = GND
  AP61  RSVD(194)  BI  = TP_CPU0_RSVD_194
  AP63  VSS(748)  GROUND  = GND
  AP65  VSS(747)  GROUND  = GND
  AP67  VSS(746)  GROUND  = GND
  AP69  VSS(745)  GROUND  = GND
  AP73  VSS(744)  GROUND  = GND
  AP75  VSS(743)  GROUND  = GND
  AP77  DDR2_DQS_DN(9)  BI  = M_C_DQS_DN<9>
  AP79  DDR1_DQS_DN(0)  BI  = M_B_DQS_DN<0>
  AP81  VSS(742)  GROUND  = GND
  AP83  VSS(741)  GROUND  = GND
  AP85  VSS(740)  GROUND  = GND
  AR2  UPI0_TX_DP(13)  OUT  = UPI_CPU0_CPU1_P0P0_DP<6>
  AR4  UPI0_TX_DP(14)  OUT  = UPI_CPU0_CPU1_P0P0_DP<5>
  AR6  VSS(1190)  GROUND  = GND
  AR8  UPI0_RX_DN(11)  IN  = UPI_CPU1_CPU0_P0P0_DN<8>
  AR10  VSS(739)  GROUND  = GND
  AR12  PREQ_N  IN  = XDP_CPU_PREQ_N
  AR14  PMSYNC  IN  = H_PM_SYNC_GTL_R1
  AR16  TEST_6  BI  = TP_CPU0_TEST_6
  AR18  SAFE_MODE_BOOT  IN  = PU_CPU0_SAFE_MODE_BOOT
  AR20  RSVD(193)  BI  = PVCCMCP_CPU0
  AR22  RSVD(192)  BI  = PVCCMCP_CPU0
  AR24  VSS(738)  GROUND  = GND
  AR26  RSVD(191)  BI  = PVCCMCP_CPU0
  AR28  VCCIO(104)  POWER  = PVCCIO_CPU0
  AR30  VSS(737)  GROUND  = GND
  AR56  VCCIN(239)  POWER  = PVCCIN_CPU0
  AR58  VCCIN(238)  POWER  = PVCCIN_CPU0
  AR60  VSS(736)  GROUND  = GND
  AR62  RSVD(190)  BI  = TP_CPU0_RSVD_190
  AR64  DDR2_DQ(27)  BI  = M_C_DQ<27>
  AR66  DDR2_DQS_DP(3)  BI  = M_C_DQS_DP<3>
  AR68  DDR2_DQ(29)  BI  = M_C_DQ<29>
  AR72  VSS(735)  GROUND  = GND
  AR74  DDR2_DQ(5)  BI  = M_C_DQ<5>
  AR76  DDR2_DQ(0)  BI  = M_C_DQ<0>
  AR78  VSS(734)  GROUND  = GND
  AR80  DDR1_DQS_DP(0)  BI  = M_B_DQS_DP<0>
  AR82  DDR1_DQ(6)  BI  = M_B_DQ<6>
  AR84  DDR0_DQ(5)  BI  = M_A_DQ<5>
  AR86  DDR0_DQ(4)  BI  = M_A_DQ<4>
  AT1  UPI0_TX_DN(12)  OUT  = UPI_CPU0_CPU1_P0P0_DN<7>
  AT3  UPI0_TX_DN(13)  OUT  = UPI_CPU0_CPU1_P0P0_DN<6>
  AT5  VCCIO(5)  POWER  = PVCCIO_CPU0
  AT7  VCCIO(6)  POWER  = PVCCIO_CPU0
  AT9  UPI0_RX_DP(12)  IN  = UPI_CPU1_CPU0_P0P0_DP<7>
  AT11  VCCIO(38)  POWER  = PVCCIO_CPU0
  AT13  RSVD(189)  BI  = TP_CPU0_RSVD_189
  AT15  VSS(731)  GROUND  = GND
  AT17  VSS(730)  GROUND  = GND
  AT19  PMSYNC_CLK  IN  = H_PMSYNC_CLK_24M_CPU0
  AT21  VSS(729)  GROUND  = GND
  AT23  RSVD(188)  BI  = PVCCMCP_CPU0
  AT25  RSVD(187)  BI  = PVCCMCP_CPU0
  AT27  VSS(728)  GROUND  = GND
  AT29  UPI01_RBIAS(0)  IN  = A_CPU0_UPI01_RBIAS
  AT57  VCCIN(237)  POWER  = PVCCIN_CPU0
  AT59  VCCIN(236)  POWER  = PVCCIN_CPU0
  AT61  VSS(727)  GROUND  = GND
  AT63  VSS(726)  GROUND  = GND
  AT65  DDR2_DQ(31)  BI  = M_C_DQ<31>
  AT67  DDR2_DQ(25)  BI  = M_C_DQ<25>
  AT69  VSS(725)  GROUND  = GND
  AT71  DDR2_DQS_DN(17)  BI  = M_C_DQS_DN<17>
  AT73  VSS(724)  GROUND  = GND
  AT75  DDR2_DQ(4)  BI  = M_C_DQ<4>
  AT77  VSS(723)  GROUND  = GND
  AT79  DDR1_DQ(1)  BI  = M_B_DQ<1>
  AT81  DDR1_DQS_DP(9)  BI  = M_B_DQS_DP<9>
  AT83  VSS(722)  GROUND  = GND
  AT85  VSS(721)  GROUND  = GND
  AU2  VSS(720)  GROUND  = GND
  AU4  UPI0_TX_DN(14)  OUT  = UPI_CPU0_CPU1_P0P0_DN<5>
  AU6  VSS(719)  GROUND  = GND
  AU8  UPI0_RX_DP(11)  IN  = UPI_CPU1_CPU0_P0P0_DP<8>
  AU10  UPI0_RX_DN(12)  IN  = UPI_CPU1_CPU0_P0P0_DN<7>
  AU12  PECI  BI  = PECI_CPU_G
  AU14  FIVR_FAULT  OUT  = H_CPU0_FIVR_FAULT_G
  AU16  SOCKET_ID(1)  IN  = PU_CPU0_SOCKET_ID_1
  AU18  TEST_7  BI  = TP_CPU0_TEST_7
  AU20  SOCKET_ID(2)  IN  = TP_CPU0_SOCKET_ID_2
  AU22  SOCKET_ID(0)  IN  = PU_CPU0_SOCKET_ID_0
  AU24  BCLK0_DN  IN  = CLK_100M_CPU0_BCLK0_DN
  AU26  VSS(718)  GROUND  = GND
  AU28  VSS(717)  GROUND  = GND
  AU58  VCCIN(235)  POWER  = PVCCIN_CPU0
  AU60  VCCIN(234)  POWER  = PVCCIN_CPU0
  AU62  VSS(716)  GROUND  = GND
  AU64  VSS(715)  GROUND  = GND
  AU66  DDR2_DQS_DN(3)  BI  = M_C_DQS_DN<3>
  AU68  VSS(714)  GROUND  = GND
  AU70  DDR2_ECC(6)  BI  = M_C_ECC<6>
  AU72  DDR2_ECC(0)  BI  = M_C_ECC<0>
  AU74  VSS(713)  GROUND  = GND
  AU76  VSS(712)  GROUND  = GND
  AU78  VSS(711)  GROUND  = GND
  AU80  VSS(710)  GROUND  = GND
  AU82  DDR1_DQS_DN(9)  BI  = M_B_DQS_DN<9>
  AU84  VSS(709)  GROUND  = GND
  AU86  VSS(708)  GROUND  = GND
  AV1  VSS(707)  GROUND  = GND
  AV3  VSS(706)  GROUND  = GND
  AV5  UPI0_TX_DN(15)  OUT  = UPI_CPU0_CPU1_P0P0_DN<4>
  AV7  VSS(705)  GROUND  = GND
  AV9  UPI0_RX_DP(16)  IN  = UPI_CPU1_CPU0_P0P0_DP<3>
  AV11  VSS(704)  GROUND  = GND
  AV13  VSS(703)  GROUND  = GND
  AV15  TXT_PLTEN  IN  = PD_CPU0_TXT_PLTEN
  AV17  FRMAGENT  IN  = PU_CPU0_FRMAGENT
  AV19  VSS(702)  GROUND  = GND
  AV21  DEBUG_EN_N  BI  = CPU_XDP_PRESENT_N
  AV23  VSS(701)  GROUND  = GND
  AV25  VSS(700)  GROUND  = GND
  AV27  VCCIO(80)  POWER  = PVCCIO_CPU0
  AV59  VCCIN(233)  POWER  = PVCCIN_CPU0
  AV61  VCCIN(232)  POWER  = PVCCIN_CPU0
  AV63  VSS(699)  GROUND  = GND
  AV65  VSS(698)  GROUND  = GND
  AV67  VSS(697)  GROUND  = GND
  AV69  DDR2_ECC(2)  BI  = M_C_ECC<2>
  AV71  DDR2_DQS_DP(17)  BI  = M_C_DQS_DP<17>
  AV73  DDR2_ECC(4)  BI  = M_C_ECC<4>
  AV75  VSS(696)  GROUND  = GND
  AV77  RSVD(186)  BI  = TP_CPU0_RSVD_186
  AV79  DDR1_DQ(5)  BI  = M_B_DQ<5>
  AV81  DDR1_DQ(0)  BI  = M_B_DQ<0>
  AV83  VSS(695)  GROUND  = GND
  AV85  VCCINPMAX(1)  POWER  = VSENSE_VCCINR2PMAX_CPU0
  AW2  VSS(694)  GROUND  = GND
  AW4  UPI0_TX_DP(15)  OUT  = UPI_CPU0_CPU1_P0P0_DP<4>
  AW6  VCCIO(37)  POWER  = PVCCIO_CPU0
  AW8  UPI0_RX_DN(16)  IN  = UPI_CPU1_CPU0_P0P0_DN<3>
  AW10  VSS(693)  GROUND  = GND
  AW12  DMIMODE_OVERRIDE  BI  = PD_CPU0_DMIMODE_OVERRIDE
  AW14  TEST_15  BI  = PD_CPU0_KSFC_DIS
